# T6G (Grand Teton) — schematic netlist excerpt (pin names and nets, part order shuffled) for the footprints in the layout excerpt that follows; sources: Cadence DE-HDL packaged netlist, KiCad conversion of 04192023_DAF0TMB3IC0_F0TG_MB_C_brd_V02_OCP.brd

PC6503  Q_CAP  22UF 16V 20% X6S  pkg C0805  page 360 : A = SW_P12V_AUX_P1V8_RETIMER_CPU0_FLT ; B = GND
PL37  Q_INDUCTOR  50NH/86A IND  pkg SMLF  page 215 : \1\ = SW_P12V_AUX_PVDDCR_SOC_P1_FLT ; \2\ = P12V_AUX
PC133_C1P0_5  Q_CAP  2.2UF 10V 10% X6S  pkg C0402  page 203 : A = PVDDCR_CPU1_P0_PVCC ; B = GND

(kicad_pcb
	(version 20260206)
	(generator "pcbnew")
	(generator_version "10.0")
	(general
		(thickness 1.6)
		(legacy_teardrops no)
	)
	(paper "A4")
	(title_block
		(title "04192023_DAF0TMB3IC0_F0TG_MB_C_brd_V02_OCP.brd")
		(comment 1 "Grand Teton / footprints 1717-1719 of 8354")
	)
	(layers
		(0 "F.Cu" signal "TOP")
		(4 "In1.Cu" signal "GND")
		(6 "In2.Cu" signal "IN1")
		(8 "In3.Cu" signal "GND1")
		(10 "In4.Cu" signal "IN2")
		(12 "In5.Cu" signal "GND2")
		(14 "In6.Cu" signal "IN3")
		(16 "In7.Cu" signal "GND3")
		(18 "In8.Cu" signal "VCC")
		(20 "In9.Cu" signal "VCC1")
		(22 "In10.Cu" signal "GND4")
		(24 "In11.Cu" signal "IN4")
		(26 "In12.Cu" signal "GND5")
		(28 "In13.Cu" signal "IN5")
		(30 "In14.Cu" signal "GND6")
		(32 "In15.Cu" signal "IN6")
		(34 "In16.Cu" signal "GND7")
		(2 "B.Cu" signal "BOTTOM")
		(9 "F.Adhes" user "F.Adhesive")
		(11 "B.Adhes" user "B.Adhesive")
		(13 "F.Paste" user "Package Geometry/Pastemask Top")
		(15 "B.Paste" user "Package Geometry/Pastemask Bottom")
		(5 "F.SilkS" user "Ref Des/Silkscreen Top")
		(7 "B.SilkS" user "Ref Des/Silkscreen Bottom")
		(1 "F.Mask" user "Board Geometry/Soldermask Top")
		(3 "B.Mask" user "Board Geometry/Soldermask Bottom")
		(17 "Dwgs.User" user "User.Drawings")
		(19 "Cmts.User" user "User.Comments")
		(21 "Eco1.User" user "User.Eco1")
		(23 "Eco2.User" user "User.Eco2")
		(25 "Edge.Cuts" user "Board Geometry/Outline")
		(27 "Margin" user)
		(31 "F.CrtYd" user "Package Geometry/Place Bound Top")
		(29 "B.CrtYd" user "Package Geometry/Place Bound Bottom")
		(35 "F.Fab" user "Ref Des/Assembly Top")
		(33 "B.Fab" user "Ref Des/Assembly Bottom")
	)
	(footprint ""
		(layer "F.Cu")
		(at 118.511574 -148.291042 -90)
		(property "Reference" "PL37"
			(at -0.575056 -3.974084 90)
			(unlocked yes)
			(layer "F.SilkS")
			(effects
				(font
					(size 0.7874 0.5842)
					(thickness 0.1524)
				)
				(justify left)
			)
		)
		(property "Value" ""
			(at 0 0 270)
			(layer "F.Fab")
			(effects
				(font
					(size 1.27 1.27)
				)
			)
		)
		(duplicate_pad_numbers_are_jumpers no)
		(fp_line
			(start -3.050032 2.999994)
			(end 3.050032 2.999994)
			(stroke
				(width 0.1524)
				(type default)
			)
			(layer "F.SilkS")
		)
		(fp_line
			(start 3.050032 2.999994)
			(end 3.050032 1.4478)
			(stroke
				(width 0.1524)
				(type default)
			)
			(layer "F.SilkS")
		)
		(fp_line
			(start -3.050032 1.4478)
			(end -3.050032 2.999994)
			(stroke
				(width 0.1524)
				(type default)
			)
			(layer "F.SilkS")
		)
		(fp_line
			(start 3.050032 -1.4478)
			(end 3.050032 -2.999994)
			(stroke
				(width 0.1524)
				(type default)
			)
			(layer "F.SilkS")
		)
		(fp_line
			(start -3.050032 -2.999994)
			(end -3.050032 -1.4478)
			(stroke
				(width 0.1524)
				(type default)
			)
			(layer "F.SilkS")
		)
		(fp_line
			(start 3.050032 -2.999994)
			(end -3.050032 -2.999994)
			(stroke
				(width 0.1524)
				(type default)
			)
			(layer "F.SilkS")
		)
		(fp_line
			(start -3.050032 2.999994)
			(end 3.050032 2.999994)
			(stroke
				(width 0.1)
				(type default)
			)
			(layer "F.Fab")
		)
		(fp_line
			(start 3.050032 2.999994)
			(end 3.050032 -2.999994)
			(stroke
				(width 0.1)
				(type default)
			)
			(layer "F.Fab")
		)
		(fp_line
			(start -3.050032 -2.999994)
			(end -3.050032 2.999994)
			(stroke
				(width 0.1)
				(type default)
			)
			(layer "F.Fab")
		)
		(fp_line
			(start 3.050032 -2.999994)
			(end -3.050032 -2.999994)
			(stroke
				(width 0.1)
				(type default)
			)
			(layer "F.Fab")
		)
		(pad "1" smd rect
			(at -2.525014 0 270)
			(size 1.651 2.6162)
			(layers "F.Cu" "F.Mask" "F.Paste")
			(net "SW_P12V_AUX_PVDDCR_SOC_P1_FLT")
		)
		(pad "2" smd rect
			(at 2.525014 0 270)
			(size 1.651 2.6162)
			(layers "F.Cu" "F.Mask" "F.Paste")
			(net "P12V_AUX")
		)
	)
	(footprint ""
		(layer "F.Cu")
		(at 339.70722 -335.022698 -90)
		(property "Reference" "PC133_C1P0_5"
			(at 0 0 270)
			(layer "F.SilkS")
			(hide yes)
			(effects
				(font
					(size 1.27 1.27)
				)
			)
		)
		(property "Value" ""
			(at 0 0 270)
			(layer "F.Fab")
			(effects
				(font
					(size 1.27 1.27)
				)
			)
		)
		(duplicate_pad_numbers_are_jumpers no)
		(fp_line
			(start -0.7874 0.4064)
			(end -0.7874 -0.4064)
			(stroke
				(width 0.1524)
				(type default)
			)
			(layer "F.SilkS")
		)
		(fp_line
			(start 0.7874 0.4064)
			(end -0.7874 0.4064)
			(stroke
				(width 0.1524)
				(type default)
			)
			(layer "F.SilkS")
		)
		(fp_line
			(start -0.7874 -0.4064)
			(end 0.7874 -0.4064)
			(stroke
				(width 0.1524)
				(type default)
			)
			(layer "F.SilkS")
		)
		(fp_line
			(start 0.7874 -0.4064)
			(end 0.7874 0.4064)
			(stroke
				(width 0.1524)
				(type default)
			)
			(layer "F.SilkS")
		)
		(fp_line
			(start -0.67945 0.3048)
			(end -0.67945 -0.305054)
			(stroke
				(width 0.1)
				(type default)
			)
			(layer "F.Fab")
		)
		(fp_line
			(start -0.12065 0.3048)
			(end -0.67945 0.3048)
			(stroke
				(width 0.1)
				(type default)
			)
			(layer "F.Fab")
		)
		(fp_line
			(start 0.120396 0.3048)
			(end 0.120396 0.2794)
			(stroke
				(width 0.1)
				(type default)
			)
			(layer "F.Fab")
		)
		(fp_line
			(start 0.67945 0.3048)
			(end 0.120396 0.3048)
			(stroke
				(width 0.1)
				(type default)
			)
			(layer "F.Fab")
		)
		(fp_line
			(start -0.12065 0.2794)
			(end -0.12065 0.3048)
			(stroke
				(width 0.1)
				(type default)
			)
			(layer "F.Fab")
		)
		(fp_line
			(start 0.120396 0.2794)
			(end -0.12065 0.2794)
			(stroke
				(width 0.1)
				(type default)
			)
			(layer "F.Fab")
		)
		(fp_line
			(start -0.12065 -0.2794)
			(end 0.12065 -0.2794)
			(stroke
				(width 0.1)
				(type default)
			)
			(layer "F.Fab")
		)
		(fp_line
			(start 0.12065 -0.2794)
			(end 0.12065 -0.3048)
			(stroke
				(width 0.1)
				(type default)
			)
			(layer "F.Fab")
		)
		(fp_line
			(start 0.12065 -0.3048)
			(end 0.67945 -0.3048)
			(stroke
				(width 0.1)
				(type default)
			)
			(layer "F.Fab")
		)
		(fp_line
			(start 0.67945 -0.3048)
			(end 0.67945 0.3048)
			(stroke
				(width 0.1)
				(type default)
			)
			(layer "F.Fab")
		)
		(fp_line
			(start -0.67945 -0.305054)
			(end -0.12065 -0.305054)
			(stroke
				(width 0.1)
				(type default)
			)
			(layer "F.Fab")
		)
		(fp_line
			(start -0.12065 -0.305054)
			(end -0.12065 -0.2794)
			(stroke
				(width 0.1)
				(type default)
			)
			(layer "F.Fab")
		)
		(pad "1" smd circle
			(at -0.40005 0 270)
			(size 0 0)
			(layers "F.Cu" "F.Mask" "F.Paste")
			(net "PVDDCR_CPU1_P0_PVCC")
		)
		(pad "2" smd circle
			(at 0.40005 0 270)
			(size 0 0)
			(layers "F.Cu" "F.Mask" "F.Paste")
			(net "GND")
		)
	)
	(footprint ""
		(layer "F.Cu")
		(at 240.792 -283.5148 180)
		(property "Reference" "PC6503"
			(at 0 0 180)
			(layer "F.SilkS")
			(hide yes)
			(effects
				(font
					(size 1.27 1.27)
				)
			)
		)
		(property "Value" ""
			(at 0 0 180)
			(layer "F.Fab")
			(effects
				(font
					(size 1.27 1.27)
				)
			)
		)
		(duplicate_pad_numbers_are_jumpers no)
		(fp_line
			(start 1.524 0.762)
			(end -1.524 0.762)
			(stroke
				(width 0.1524)
				(type default)
			)
			(layer "F.SilkS")
		)
		(fp_line
			(start 1.524 -0.762)
			(end 1.524 0.762)
			(stroke
				(width 0.1524)
				(type default)
			)
			(layer "F.SilkS")
		)
		(fp_line
			(start -1.524 0.762)
			(end -1.524 -0.762)
			(stroke
				(width 0.1524)
				(type default)
			)
			(layer "F.SilkS")
		)
		(fp_line
			(start -1.524 -0.762)
			(end 1.524 -0.762)
			(stroke
				(width 0.1524)
				(type default)
			)
			(layer "F.SilkS")
		)
		(fp_line
			(start 1.1049 0.724916)
			(end 1.1049 -0.724916)
			(stroke
				(width 0.1)
				(type default)
			)
			(layer "F.Fab")
		)
		(fp_line
			(start 1.1049 -0.724916)
			(end -1.1049 -0.724916)
			(stroke
				(width 0.1)
				(type default)
			)
			(layer "F.Fab")
		)
		(fp_line
			(start -1.1049 0.724916)
			(end 1.1049 0.724916)
			(stroke
				(width 0.1)
				(type default)
			)
			(layer "F.Fab")
		)
		(fp_line
			(start -1.1049 -0.724916)
			(end -1.1049 0.724916)
			(stroke
				(width 0.1)
				(type default)
			)
			(layer "F.Fab")
		)
		(pad "1" smd rect
			(at -0.889 0)
			(size 1.016 1.27)
			(layers "F.Cu" "F.Mask" "F.Paste")
			(net "SW_P12V_AUX_P1V8_RETIMER_CPU0_FLT")
		)
		(pad "2" smd rect
			(at 0.889 0)
			(size 1.016 1.27)
			(layers "F.Cu" "F.Mask" "F.Paste")
			(net "GND")
		)
	)
)
